(kicad_pcb
	(version 20260206)
	(generator "pcbnew")
	(generator_version "10.0")
	(general
		(thickness 1.6)
		(legacy_teardrops no)
	)
	(paper "A4")
	(title_block
		(title "12092022_DA0F0TMDCD0_F0T_Management_Board_D_brd_V3_OCP.brd")
		(comment 1 "Grand Teton / footprints 455-460 of 1440")
	)
	(layers
		(0 "F.Cu" signal "TOP")
		(4 "In1.Cu" signal "GND")
		(6 "In2.Cu" signal "IN1")
		(8 "In3.Cu" signal "GND1")
		(10 "In4.Cu" signal "IN2")
		(12 "In5.Cu" signal "VCC")
		(14 "In6.Cu" signal "VCC1")
		(16 "In7.Cu" signal "IN3")
		(18 "In8.Cu" signal "GND2")
		(20 "In9.Cu" signal "IN4")
		(22 "In10.Cu" signal "GND3")
		(2 "B.Cu" signal "BOTTOM")
		(9 "F.Adhes" user "F.Adhesive")
		(11 "B.Adhes" user "B.Adhesive")
		(13 "F.Paste" user "Package Geometry/Pastemask Top")
		(15 "B.Paste" user "Package Geometry/Pastemask Bottom")
		(5 "F.SilkS" user "Ref Des/Silkscreen Top")
		(7 "B.SilkS" user "Ref Des/Silkscreen Bottom")
		(1 "F.Mask" user "Board Geometry/Soldermask Top")
		(3 "B.Mask" user "Board Geometry/Soldermask Bottom")
		(17 "Dwgs.User" user "User.Drawings")
		(19 "Cmts.User" user "User.Comments")
		(21 "Eco1.User" user "User.Eco1")
		(23 "Eco2.User" user "User.Eco2")
		(25 "Edge.Cuts" user "Board Geometry/Outline")
		(27 "Margin" user)
		(31 "F.CrtYd" user "Package Geometry/Place Bound Top")
		(29 "B.CrtYd" user "Package Geometry/Place Bound Bottom")
		(35 "F.Fab" user "Ref Des/Assembly Top")
		(33 "B.Fab" user "Ref Des/Assembly Bottom")
	)
	(footprint ""
		(layer "F.Cu")
		(at 57.023 -75.3364 180)
		(property "Reference" "R545"
			(at 0 0 180)
			(layer "F.SilkS")
			(hide yes)
			(effects
				(font
					(size 1.27 1.27)
				)
			)
		)
		(property "Value" ""
			(at 0 0 180)
			(layer "F.Fab")
			(effects
				(font
					(size 1.27 1.27)
				)
			)
		)
		(duplicate_pad_numbers_are_jumpers no)
		(fp_line
			(start 0.7874 0.4064)
			(end -0.7874 0.4064)
			(stroke
				(width 0.1524)
				(type default)
			)
			(layer "F.SilkS")
		)
		(fp_line
			(start 0.7874 -0.4064)
			(end 0.7874 0.4064)
			(stroke
				(width 0.1524)
				(type default)
			)
			(layer "F.SilkS")
		)
		(fp_line
			(start -0.7874 0.4064)
			(end -0.7874 -0.4064)
			(stroke
				(width 0.1524)
				(type default)
			)
			(layer "F.SilkS")
		)
		(fp_line
			(start -0.7874 -0.4064)
			(end 0.7874 -0.4064)
			(stroke
				(width 0.1524)
				(type default)
			)
			(layer "F.SilkS")
		)
		(fp_line
			(start 0.67945 0.3048)
			(end 0.120396 0.3048)
			(stroke
				(width 0.1)
				(type default)
			)
			(layer "F.Fab")
		)
		(fp_line
			(start 0.67945 -0.3048)
			(end 0.67945 0.3048)
			(stroke
				(width 0.1)
				(type default)
			)
			(layer "F.Fab")
		)
		(fp_line
			(start 0.12065 -0.2794)
			(end 0.12065 -0.3048)
			(stroke
				(width 0.1)
				(type default)
			)
			(layer "F.Fab")
		)
		(fp_line
			(start 0.12065 -0.3048)
			(end 0.67945 -0.3048)
			(stroke
				(width 0.1)
				(type default)
			)
			(layer "F.Fab")
		)
		(fp_line
			(start 0.120396 0.3048)
			(end 0.120396 0.2794)
			(stroke
				(width 0.1)
				(type default)
			)
			(layer "F.Fab")
		)
		(fp_line
			(start 0.120396 0.2794)
			(end -0.12065 0.2794)
			(stroke
				(width 0.1)
				(type default)
			)
			(layer "F.Fab")
		)
		(fp_line
			(start -0.12065 0.3048)
			(end -0.67945 0.3048)
			(stroke
				(width 0.1)
				(type default)
			)
			(layer "F.Fab")
		)
		(fp_line
			(start -0.12065 0.2794)
			(end -0.12065 0.3048)
			(stroke
				(width 0.1)
				(type default)
			)
			(layer "F.Fab")
		)
		(fp_line
			(start -0.12065 -0.2794)
			(end 0.12065 -0.2794)
			(stroke
				(width 0.1)
				(type default)
			)
			(layer "F.Fab")
		)
		(fp_line
			(start -0.12065 -0.305054)
			(end -0.12065 -0.2794)
			(stroke
				(width 0.1)
				(type default)
			)
			(layer "F.Fab")
		)
		(fp_line
			(start -0.67945 0.3048)
			(end -0.67945 -0.305054)
			(stroke
				(width 0.1)
				(type default)
			)
			(layer "F.Fab")
		)
		(fp_line
			(start -0.67945 -0.305054)
			(end -0.12065 -0.305054)
			(stroke
				(width 0.1)
				(type default)
			)
			(layer "F.Fab")
		)
		(pad "1" smd circle
			(at -0.40005 0 180)
			(size 0 0)
			(layers "F.Cu" "F.Mask" "F.Paste")
			(net "GND")
		)
		(pad "2" smd circle
			(at 0.40005 0 180)
			(size 0 0)
			(layers "F.Cu" "F.Mask" "F.Paste")
			(net "FLASH_LATCH_CP")
		)
	)
	(footprint ""
		(layer "F.Cu")
		(at 60.198 -10.922 90)
		(property "Reference" "R80"
			(at 0 0 90)
			(layer "F.SilkS")
			(hide yes)
			(effects
				(font
					(size 1.27 1.27)
				)
			)
		)
		(property "Value" ""
			(at 0 0 90)
			(layer "F.Fab")
			(effects
				(font
					(size 1.27 1.27)
				)
			)
		)
		(duplicate_pad_numbers_are_jumpers no)
		(fp_line
			(start 0.7874 -0.4064)
			(end 0.7874 0.4064)
			(stroke
				(width 0.1524)
				(type default)
			)
			(layer "F.SilkS")
		)
		(fp_line
			(start -0.7874 -0.4064)
			(end 0.7874 -0.4064)
			(stroke
				(width 0.1524)
				(type default)
			)
			(layer "F.SilkS")
		)
		(fp_line
			(start 0.7874 0.4064)
			(end -0.7874 0.4064)
			(stroke
				(width 0.1524)
				(type default)
			)
			(layer "F.SilkS")
		)
		(fp_line
			(start -0.7874 0.4064)
			(end -0.7874 -0.4064)
			(stroke
				(width 0.1524)
				(type default)
			)
			(layer "F.SilkS")
		)
		(fp_line
			(start -0.12065 -0.305054)
			(end -0.12065 -0.2794)
			(stroke
				(width 0.1)
				(type default)
			)
			(layer "F.Fab")
		)
		(fp_line
			(start -0.67945 -0.305054)
			(end -0.12065 -0.305054)
			(stroke
				(width 0.1)
				(type default)
			)
			(layer "F.Fab")
		)
		(fp_line
			(start 0.67945 -0.3048)
			(end 0.67945 0.3048)
			(stroke
				(width 0.1)
				(type default)
			)
			(layer "F.Fab")
		)
		(fp_line
			(start 0.12065 -0.3048)
			(end 0.67945 -0.3048)
			(stroke
				(width 0.1)
				(type default)
			)
			(layer "F.Fab")
		)
		(fp_line
			(start 0.12065 -0.2794)
			(end 0.12065 -0.3048)
			(stroke
				(width 0.1)
				(type default)
			)
			(layer "F.Fab")
		)
		(fp_line
			(start -0.12065 -0.2794)
			(end 0.12065 -0.2794)
			(stroke
				(width 0.1)
				(type default)
			)
			(layer "F.Fab")
		)
		(fp_line
			(start 0.120396 0.2794)
			(end -0.12065 0.2794)
			(stroke
				(width 0.1)
				(type default)
			)
			(layer "F.Fab")
		)
		(fp_line
			(start -0.12065 0.2794)
			(end -0.12065 0.3048)
			(stroke
				(width 0.1)
				(type default)
			)
			(layer "F.Fab")
		)
		(fp_line
			(start 0.67945 0.3048)
			(end 0.120396 0.3048)
			(stroke
				(width 0.1)
				(type default)
			)
			(layer "F.Fab")
		)
		(fp_line
			(start 0.120396 0.3048)
			(end 0.120396 0.2794)
			(stroke
				(width 0.1)
				(type default)
			)
			(layer "F.Fab")
		)
		(fp_line
			(start -0.12065 0.3048)
			(end -0.67945 0.3048)
			(stroke
				(width 0.1)
				(type default)
			)
			(layer "F.Fab")
		)
		(fp_line
			(start -0.67945 0.3048)
			(end -0.67945 -0.305054)
			(stroke
				(width 0.1)
				(type default)
			)
			(layer "F.Fab")
		)
		(pad "1" smd circle
			(at -0.40005 0 90)
			(size 0 0)
			(layers "F.Cu" "F.Mask" "F.Paste")
			(net "LED_D22_R")
		)
		(pad "2" smd circle
			(at 0.40005 0 90)
			(size 0 0)
			(layers "F.Cu" "F.Mask" "F.Paste")
			(net "P5V_AUX")
		)
	)
	(footprint ""
		(layer "F.Cu")
		(at 72.644 -10.922 90)
		(property "Reference" "R471"
			(at 0 0 90)
			(layer "F.SilkS")
			(hide yes)
			(effects
				(font
					(size 1.27 1.27)
				)
			)
		)
		(property "Value" ""
			(at 0 0 90)
			(layer "F.Fab")
			(effects
				(font
					(size 1.27 1.27)
				)
			)
		)
		(duplicate_pad_numbers_are_jumpers no)
		(fp_line
			(start 0.7874 -0.4064)
			(end 0.7874 0.4064)
			(stroke
				(width 0.1524)
				(type default)
			)
			(layer "F.SilkS")
		)
		(fp_line
			(start -0.7874 -0.4064)
			(end 0.7874 -0.4064)
			(stroke
				(width 0.1524)
				(type default)
			)
			(layer "F.SilkS")
		)
		(fp_line
			(start 0.7874 0.4064)
			(end -0.7874 0.4064)
			(stroke
				(width 0.1524)
				(type default)
			)
			(layer "F.SilkS")
		)
		(fp_line
			(start -0.7874 0.4064)
			(end -0.7874 -0.4064)
			(stroke
				(width 0.1524)
				(type default)
			)
			(layer "F.SilkS")
		)
		(fp_line
			(start -0.12065 -0.305054)
			(end -0.12065 -0.2794)
			(stroke
				(width 0.1)
				(type default)
			)
			(layer "F.Fab")
		)
		(fp_line
			(start -0.67945 -0.305054)
			(end -0.12065 -0.305054)
			(stroke
				(width 0.1)
				(type default)
			)
			(layer "F.Fab")
		)
		(fp_line
			(start 0.67945 -0.3048)
			(end 0.67945 0.3048)
			(stroke
				(width 0.1)
				(type default)
			)
			(layer "F.Fab")
		)
		(fp_line
			(start 0.12065 -0.3048)
			(end 0.67945 -0.3048)
			(stroke
				(width 0.1)
				(type default)
			)
			(layer "F.Fab")
		)
		(fp_line
			(start 0.12065 -0.2794)
			(end 0.12065 -0.3048)
			(stroke
				(width 0.1)
				(type default)
			)
			(layer "F.Fab")
		)
		(fp_line
			(start -0.12065 -0.2794)
			(end 0.12065 -0.2794)
			(stroke
				(width 0.1)
				(type default)
			)
			(layer "F.Fab")
		)
		(fp_line
			(start 0.120396 0.2794)
			(end -0.12065 0.2794)
			(stroke
				(width 0.1)
				(type default)
			)
			(layer "F.Fab")
		)
		(fp_line
			(start -0.12065 0.2794)
			(end -0.12065 0.3048)
			(stroke
				(width 0.1)
				(type default)
			)
			(layer "F.Fab")
		)
		(fp_line
			(start 0.67945 0.3048)
			(end 0.120396 0.3048)
			(stroke
				(width 0.1)
				(type default)
			)
			(layer "F.Fab")
		)
		(fp_line
			(start 0.120396 0.3048)
			(end 0.120396 0.2794)
			(stroke
				(width 0.1)
				(type default)
			)
			(layer "F.Fab")
		)
		(fp_line
			(start -0.12065 0.3048)
			(end -0.67945 0.3048)
			(stroke
				(width 0.1)
				(type default)
			)
			(layer "F.Fab")
		)
		(fp_line
			(start -0.67945 0.3048)
			(end -0.67945 -0.305054)
			(stroke
				(width 0.1)
				(type default)
			)
			(layer "F.Fab")
		)
		(pad "1" smd circle
			(at -0.40005 0 90)
			(size 0 0)
			(layers "F.Cu" "F.Mask" "F.Paste")
			(net "REAR_AC_PWR_BTN")
		)
		(pad "2" smd circle
			(at 0.40005 0 90)
			(size 0 0)
			(layers "F.Cu" "F.Mask" "F.Paste")
			(net "AC_PWR_BTN_N")
		)
	)
	(footprint ""
		(layer "F.Cu")
		(at 73.152 -74.295 90)
		(property "Reference" "R431"
			(at 0 0 90)
			(layer "F.SilkS")
			(hide yes)
			(effects
				(font
					(size 1.27 1.27)
				)
			)
		)
		(property "Value" ""
			(at 0 0 90)
			(layer "F.Fab")
			(effects
				(font
					(size 1.27 1.27)
				)
			)
		)
		(duplicate_pad_numbers_are_jumpers no)
		(fp_line
			(start 0.7874 -0.4064)
			(end 0.7874 0.4064)
			(stroke
				(width 0.1524)
				(type default)
			)
			(layer "F.SilkS")
		)
		(fp_line
			(start -0.7874 -0.4064)
			(end 0.7874 -0.4064)
			(stroke
				(width 0.1524)
				(type default)
			)
			(layer "F.SilkS")
		)
		(fp_line
			(start 0.7874 0.4064)
			(end -0.7874 0.4064)
			(stroke
				(width 0.1524)
				(type default)
			)
			(layer "F.SilkS")
		)
		(fp_line
			(start -0.7874 0.4064)
			(end -0.7874 -0.4064)
			(stroke
				(width 0.1524)
				(type default)
			)
			(layer "F.SilkS")
		)
		(fp_line
			(start -0.12065 -0.305054)
			(end -0.12065 -0.2794)
			(stroke
				(width 0.1)
				(type default)
			)
			(layer "F.Fab")
		)
		(fp_line
			(start -0.67945 -0.305054)
			(end -0.12065 -0.305054)
			(stroke
				(width 0.1)
				(type default)
			)
			(layer "F.Fab")
		)
		(fp_line
			(start 0.67945 -0.3048)
			(end 0.67945 0.3048)
			(stroke
				(width 0.1)
				(type default)
			)
			(layer "F.Fab")
		)
		(fp_line
			(start 0.12065 -0.3048)
			(end 0.67945 -0.3048)
			(stroke
				(width 0.1)
				(type default)
			)
			(layer "F.Fab")
		)
		(fp_line
			(start 0.12065 -0.2794)
			(end 0.12065 -0.3048)
			(stroke
				(width 0.1)
				(type default)
			)
			(layer "F.Fab")
		)
		(fp_line
			(start -0.12065 -0.2794)
			(end 0.12065 -0.2794)
			(stroke
				(width 0.1)
				(type default)
			)
			(layer "F.Fab")
		)
		(fp_line
			(start 0.120396 0.2794)
			(end -0.12065 0.2794)
			(stroke
				(width 0.1)
				(type default)
			)
			(layer "F.Fab")
		)
		(fp_line
			(start -0.12065 0.2794)
			(end -0.12065 0.3048)
			(stroke
				(width 0.1)
				(type default)
			)
			(layer "F.Fab")
		)
		(fp_line
			(start 0.67945 0.3048)
			(end 0.120396 0.3048)
			(stroke
				(width 0.1)
				(type default)
			)
			(layer "F.Fab")
		)
		(fp_line
			(start 0.120396 0.3048)
			(end 0.120396 0.2794)
			(stroke
				(width 0.1)
				(type default)
			)
			(layer "F.Fab")
		)
		(fp_line
			(start -0.12065 0.3048)
			(end -0.67945 0.3048)
			(stroke
				(width 0.1)
				(type default)
			)
			(layer "F.Fab")
		)
		(fp_line
			(start -0.67945 0.3048)
			(end -0.67945 -0.305054)
			(stroke
				(width 0.1)
				(type default)
			)
			(layer "F.Fab")
		)
		(pad "1" smd circle
			(at -0.40005 0 90)
			(size 0 0)
			(layers "F.Cu" "F.Mask" "F.Paste")
			(net "FM_BMC_DISABLE")
		)
		(pad "2" smd circle
			(at 0.40005 0 90)
			(size 0 0)
			(layers "F.Cu" "F.Mask" "F.Paste")
			(net "GND")
		)
	)
	(footprint ""
		(layer "F.Cu")
		(at 31.115 -64.8208 -90)
		(property "Reference" "R530"
			(at 0 0 270)
			(layer "F.SilkS")
			(hide yes)
			(effects
				(font
					(size 1.27 1.27)
				)
			)
		)
		(property "Value" ""
			(at 0 0 270)
			(layer "F.Fab")
			(effects
				(font
					(size 1.27 1.27)
				)
			)
		)
		(duplicate_pad_numbers_are_jumpers no)
		(fp_line
			(start -0.7874 0.4064)
			(end -0.7874 -0.4064)
			(stroke
				(width 0.1524)
				(type default)
			)
			(layer "F.SilkS")
		)
		(fp_line
			(start 0.7874 0.4064)
			(end -0.7874 0.4064)
			(stroke
				(width 0.1524)
				(type default)
			)
			(layer "F.SilkS")
		)
		(fp_line
			(start -0.7874 -0.4064)
			(end 0.7874 -0.4064)
			(stroke
				(width 0.1524)
				(type default)
			)
			(layer "F.SilkS")
		)
		(fp_line
			(start 0.7874 -0.4064)
			(end 0.7874 0.4064)
			(stroke
				(width 0.1524)
				(type default)
			)
			(layer "F.SilkS")
		)
		(fp_line
			(start -0.67945 0.3048)
			(end -0.67945 -0.305054)
			(stroke
				(width 0.1)
				(type default)
			)
			(layer "F.Fab")
		)
		(fp_line
			(start -0.12065 0.3048)
			(end -0.67945 0.3048)
			(stroke
				(width 0.1)
				(type default)
			)
			(layer "F.Fab")
		)
		(fp_line
			(start 0.120396 0.3048)
			(end 0.120396 0.2794)
			(stroke
				(width 0.1)
				(type default)
			)
			(layer "F.Fab")
		)
		(fp_line
			(start 0.67945 0.3048)
			(end 0.120396 0.3048)
			(stroke
				(width 0.1)
				(type default)
			)
			(layer "F.Fab")
		)
		(fp_line
			(start -0.12065 0.2794)
			(end -0.12065 0.3048)
			(stroke
				(width 0.1)
				(type default)
			)
			(layer "F.Fab")
		)
		(fp_line
			(start 0.120396 0.2794)
			(end -0.12065 0.2794)
			(stroke
				(width 0.1)
				(type default)
			)
			(layer "F.Fab")
		)
		(fp_line
			(start -0.12065 -0.2794)
			(end 0.12065 -0.2794)
			(stroke
				(width 0.1)
				(type default)
			)
			(layer "F.Fab")
		)
		(fp_line
			(start 0.12065 -0.2794)
			(end 0.12065 -0.3048)
			(stroke
				(width 0.1)
				(type default)
			)
			(layer "F.Fab")
		)
		(fp_line
			(start 0.12065 -0.3048)
			(end 0.67945 -0.3048)
			(stroke
				(width 0.1)
				(type default)
			)
			(layer "F.Fab")
		)
		(fp_line
			(start 0.67945 -0.3048)
			(end 0.67945 0.3048)
			(stroke
				(width 0.1)
				(type default)
			)
			(layer "F.Fab")
		)
		(fp_line
			(start -0.67945 -0.305054)
			(end -0.12065 -0.305054)
			(stroke
				(width 0.1)
				(type default)
			)
			(layer "F.Fab")
		)
		(fp_line
			(start -0.12065 -0.305054)
			(end -0.12065 -0.2794)
			(stroke
				(width 0.1)
				(type default)
			)
			(layer "F.Fab")
		)
		(pad "1" smd circle
			(at -0.40005 0 270)
			(size 0 0)
			(layers "F.Cu" "F.Mask" "F.Paste")
			(net "PWRGD_P3V3_RGM")
		)
		(pad "2" smd circle
			(at 0.40005 0 270)
			(size 0 0)
			(layers "F.Cu" "F.Mask" "F.Paste")
			(net "PWRGD_P3V3_RGM_R2")
		)
	)
	(footprint ""
		(layer "F.Cu")
		(at 20.0025 -105.9942 180)
		(property "Reference" "U12"
			(at -1.1303 2.28473 0)
			(unlocked yes)
			(layer "F.SilkS")
			(effects
				(font
					(size 0.7874 0.5842)
					(thickness 0.1524)
				)
			)
		)
		(property "Value" ""
			(at 0 0 180)
			(layer "F.Fab")
			(effects
				(font
					(size 1.27 1.27)
				)
			)
		)
		(duplicate_pad_numbers_are_jumpers no)
		(fp_line
			(start 1.949958 1.610106)
			(end -1.949958 1.610106)
			(stroke
				(width 0.1524)
				(type default)
			)
			(layer "F.SilkS")
		)
		(fp_line
			(start 1.949958 -1.560068)
			(end 1.949958 1.610106)
			(stroke
				(width 0.1524)
				(type default)
			)
			(layer "F.SilkS")
		)
		(fp_line
			(start -1.949958 1.610106)
			(end -1.949958 -1.610106)
			(stroke
				(width 0.1524)
				(type default)
			)
			(layer "F.SilkS")
		)
		(fp_line
			(start -1.949958 -1.610106)
			(end 1.949958 -1.610106)
			(stroke
				(width 0.1524)
				(type default)
			)
			(layer "F.SilkS")
		)
		(fp_line
			(start 0.750062 1.560068)
			(end -0.750062 1.560068)
			(stroke
				(width 0.1)
				(type default)
			)
			(layer "F.Fab")
		)
		(fp_line
			(start 0.750062 -1.560068)
			(end 0.750062 1.560068)
			(stroke
				(width 0.1)
				(type default)
			)
			(layer "F.Fab")
		)
		(fp_line
			(start -0.750062 1.560068)
			(end -0.750062 -1.560068)
			(stroke
				(width 0.1)
				(type default)
			)
			(layer "F.Fab")
		)
		(fp_line
			(start -0.750062 -1.560068)
			(end 0.750062 -1.560068)
			(stroke
				(width 0.1)
				(type default)
			)
			(layer "F.Fab")
		)
		(pad "D" smd rect
			(at 1.100074 0 90)
			(size 1.016 1.4224)
			(layers "F.Cu" "F.Mask" "F.Paste")
			(net "RST_BMC_EXTRST_R1_N")
		)
		(pad "G" smd rect
			(at -1.100074 -0.94996 90)
			(size 1.016 1.4224)
			(layers "F.Cu" "F.Mask" "F.Paste")
			(net "RST_BMC_SELF_HW_D_C")
		)
		(pad "S" smd rect
			(at -1.100074 0.94996 90)
			(size 1.016 1.4224)
			(layers "F.Cu" "F.Mask" "F.Paste")
			(net "GND")
		)
	)
)
